(kicad_pcb
	(version 20260206)
	(generator "pcbnew")
	(generator_version "10.0")
	(general
		(thickness 1.6)
		(legacy_teardrops no)
	)
	(paper "A4")
	(title_block
		(title "Bryce Canyon_LED_16347-1_OCP.brd")
		(comment 1 "Bryce Canyon / footprints 37-42 of 49")
	)
	(layers
		(0 "F.Cu" signal "TOP")
		(2 "B.Cu" signal "BOTTOM")
		(9 "F.Adhes" user "F.Adhesive")
		(11 "B.Adhes" user "B.Adhesive")
		(13 "F.Paste" user "Package Geometry/Pastemask Top")
		(15 "B.Paste" user "Package Geometry/Pastemask Bottom")
		(5 "F.SilkS" user "Ref Des/Silkscreen Top")
		(7 "B.SilkS" user "Ref Des/Silkscreen Bottom")
		(1 "F.Mask" user "Board Geometry/Soldermask Top")
		(3 "B.Mask" user "Board Geometry/Soldermask Bottom")
		(17 "Dwgs.User" user "User.Drawings")
		(19 "Cmts.User" user "User.Comments")
		(21 "Eco1.User" user "User.Eco1")
		(23 "Eco2.User" user "User.Eco2")
		(25 "Edge.Cuts" user "Board Geometry/Outline")
		(27 "Margin" user)
		(31 "F.CrtYd" user "Package Geometry/Place Bound Top")
		(29 "B.CrtYd" user "Package Geometry/Place Bound Bottom")
		(35 "F.Fab" user "Ref Des/Assembly Top")
		(33 "B.Fab" user "Ref Des/Assembly Bottom")
	)
	(footprint ""
		(layer "B.Cu")
		(at 19.3548 -2.8956 -90)
		(property "Reference" "R13"
			(at 0 0 90)
			(layer "B.SilkS")
			(hide yes)
			(effects
				(font
					(size 1.27 1.27)
				)
				(justify mirror)
			)
		)
		(property "Value" "4K7R2F-GP"
			(at -0.064008 -3.993896 270)
			(unlocked yes)
			(layer "B.Fab")
			(hide yes)
			(effects
				(font
					(size 1.016 1.016)
					(thickness 0.1524)
				)
				(justify mirror)
			)
		)
		(property "Device Type" "R402H16"
			(at -0.064008 -5.517896 270)
			(unlocked yes)
			(layer "B.Fab")
			(hide yes)
			(effects
				(font
					(size 1.016 1.016)
					(thickness 0.1524)
				)
				(justify mirror)
			)
		)
		(duplicate_pad_numbers_are_jumpers no)
		(fp_line
			(start -0.508 -0.9398)
			(end 0.508 -0.9398)
			(stroke
				(width 0.1524)
				(type default)
			)
			(layer "B.SilkS")
		)
		(fp_line
			(start 0.508 -0.9398)
			(end 0.508 0.9398)
			(stroke
				(width 0.1524)
				(type default)
			)
			(layer "B.SilkS")
		)
		(fp_rect
			(start 0.508 0.9398)
			(end -0.508 -0.9398)
			(stroke
				(width 0)
				(type default)
			)
			(fill no)
			(layer "B.CrtYd")
		)
		(fp_rect
			(start 0.508 0.9398)
			(end -0.508 -0.9398)
			(stroke
				(width 0)
				(type default)
			)
			(fill no)
			(layer "B.Fab")
		)
		(pad "1" smd custom
			(at 0 -0.4445 90)
			(size 0.1397 0.1397)
			(layers "B.Cu" "B.Mask" "B.Paste")
			(net "DRIVE_A_24_30_FLT_LED")
			(options
				(clearance outline)
				(anchor circle)
			)
			(primitives
				(gr_poly
					(pts
						(arc
							(start -0.1778 0.2794)
							(mid -0.249642 0.249642)
							(end -0.2794 0.1778)
						)
						(arc
							(start -0.2794 -0.1778)
							(mid -0.249642 -0.249642)
							(end -0.1778 -0.2794)
						)
						(arc
							(start 0.1778 -0.2794)
							(mid 0.249642 -0.249642)
							(end 0.2794 -0.1778)
						)
						(arc
							(start 0.2794 0.1778)
							(mid 0.249642 0.249642)
							(end 0.1778 0.2794)
						)
					)
					(width 0)
					(fill yes)
				)
			)
		)
		(pad "2" smd custom
			(at 0 0.4445 90)
			(size 0.1397 0.1397)
			(layers "B.Cu" "B.Mask" "B.Paste")
			(net "GND")
			(options
				(clearance outline)
				(anchor circle)
			)
			(primitives
				(gr_poly
					(pts
						(arc
							(start -0.1778 0.2794)
							(mid -0.249642 0.249642)
							(end -0.2794 0.1778)
						)
						(arc
							(start -0.2794 -0.1778)
							(mid -0.249642 -0.249642)
							(end -0.1778 -0.2794)
						)
						(arc
							(start 0.1778 -0.2794)
							(mid 0.249642 -0.249642)
							(end 0.2794 -0.1778)
						)
						(arc
							(start 0.2794 0.1778)
							(mid 0.249642 0.249642)
							(end 0.1778 0.2794)
						)
					)
					(width 0)
					(fill yes)
				)
			)
		)
	)
	(footprint ""
		(layer "B.Cu")
		(at 34.417 -5.588 180)
		(property "Reference" "R4"
			(at 0 0 0)
			(layer "B.SilkS")
			(hide yes)
			(effects
				(font
					(size 1.27 1.27)
				)
				(justify mirror)
			)
		)
		(property "Value" "91R3F-1-GP"
			(at 0.0254 -2.5146 180)
			(unlocked yes)
			(layer "B.Fab")
			(hide yes)
			(effects
				(font
					(size 1.016 1.016)
					(thickness 0.1524)
				)
				(justify mirror)
			)
		)
		(property "Device Type" "R603H22"
			(at 0.0254 -4.0386 180)
			(unlocked yes)
			(layer "B.Fab")
			(hide yes)
			(effects
				(font
					(size 1.016 1.016)
					(thickness 0.1524)
				)
				(justify mirror)
			)
		)
		(duplicate_pad_numbers_are_jumpers no)
		(fp_line
			(start 0.4826 0)
			(end 0.2032 0)
			(stroke
				(width 0.2032)
				(type default)
			)
			(layer "B.SilkS")
		)
		(fp_line
			(start -0.2032 0)
			(end -0.4826 0)
			(stroke
				(width 0.2032)
				(type default)
			)
			(layer "B.SilkS")
		)
		(fp_rect
			(start 0.5842 1.3335)
			(end -0.5842 -1.3335)
			(stroke
				(width 0)
				(type default)
			)
			(fill no)
			(layer "B.CrtYd")
		)
		(fp_rect
			(start 0.5842 1.3335)
			(end -0.5842 -1.3335)
			(stroke
				(width 0)
				(type default)
			)
			(fill no)
			(layer "B.Fab")
		)
		(pad "1" smd custom
			(at 0 -0.762)
			(size 0.2159 0.2159)
			(layers "B.Cu" "B.Mask" "B.Paste")
			(net "P5V_A")
			(options
				(clearance outline)
				(anchor circle)
			)
			(primitives
				(gr_poly
					(pts
						(arc
							(start -0.3302 0.4318)
							(mid -0.402042 0.402042)
							(end -0.4318 0.3302)
						)
						(arc
							(start -0.4318 -0.3302)
							(mid -0.402042 -0.402042)
							(end -0.3302 -0.4318)
						)
						(arc
							(start 0.3302 -0.4318)
							(mid 0.402042 -0.402042)
							(end 0.4318 -0.3302)
						)
						(arc
							(start 0.4318 0.3302)
							(mid 0.402042 0.402042)
							(end 0.3302 0.4318)
						)
					)
					(width 0)
					(fill yes)
				)
			)
		)
		(pad "2" smd custom
			(at 0 0.762)
			(size 0.2159 0.2159)
			(layers "B.Cu" "B.Mask" "B.Paste")
			(net "DRV_ACT_25_31")
			(options
				(clearance outline)
				(anchor circle)
			)
			(primitives
				(gr_poly
					(pts
						(arc
							(start -0.3302 0.4318)
							(mid -0.402042 0.402042)
							(end -0.4318 0.3302)
						)
						(arc
							(start -0.4318 -0.3302)
							(mid -0.402042 -0.402042)
							(end -0.3302 -0.4318)
						)
						(arc
							(start 0.3302 -0.4318)
							(mid 0.402042 -0.402042)
							(end 0.4318 -0.3302)
						)
						(arc
							(start 0.4318 0.3302)
							(mid 0.402042 0.402042)
							(end 0.3302 0.4318)
						)
					)
					(width 0)
					(fill yes)
				)
			)
		)
	)
	(footprint ""
		(layer "B.Cu")
		(at 165.5318 -5.588)
		(property "Reference" "Q12"
			(at 0 0 0)
			(layer "B.SilkS")
			(hide yes)
			(effects
				(font
					(size 1.27 1.27)
				)
				(justify mirror)
			)
		)
		(property "Value" "SSM3K324R-GP"
			(at -0.127 -8.9662 0)
			(unlocked yes)
			(layer "B.Fab")
			(hide yes)
			(effects
				(font
					(size 1.016 1.016)
					(thickness 0.1524)
				)
				(justify mirror)
			)
		)
		(property "Device Type" "SOT23DGS2D4H35"
			(at -0.127 -10.4902 0)
			(unlocked yes)
			(layer "B.Fab")
			(hide yes)
			(effects
				(font
					(size 1.016 1.016)
					(thickness 0.1524)
				)
				(justify mirror)
			)
		)
		(duplicate_pad_numbers_are_jumpers no)
		(fp_line
			(start -1.651 -1.778)
			(end 1.651 -1.778)
			(stroke
				(width 0.1524)
				(type default)
			)
			(layer "B.SilkS")
		)
		(fp_line
			(start -1.651 1.778)
			(end -1.651 -1.778)
			(stroke
				(width 0.1524)
				(type default)
			)
			(layer "B.SilkS")
		)
		(fp_line
			(start 1.651 -1.778)
			(end 1.651 1.778)
			(stroke
				(width 0.1524)
				(type default)
			)
			(layer "B.SilkS")
		)
		(fp_line
			(start 1.651 1.778)
			(end -1.651 1.778)
			(stroke
				(width 0.1524)
				(type default)
			)
			(layer "B.SilkS")
		)
		(fp_poly
			(pts
				(xy 1.778 1.8796) (xy 1.778 -1.8796) (xy -1.778 -1.8796) (xy -1.778 1.8796)
			)
			(stroke
				(width 0)
				(type default)
			)
			(fill no)
			(layer "B.CrtYd")
		)
		(fp_poly
			(pts
				(xy 1.778 1.8796) (xy 1.778 -1.8796) (xy -1.778 -1.8796) (xy -1.778 1.8796)
			)
			(stroke
				(width 0)
				(type default)
			)
			(fill no)
			(layer "B.Fab")
		)
		(pad "D" smd custom
			(at 0 -0.9525 180)
			(size 0.1905 0.1905)
			(layers "B.Cu" "B.Mask" "B.Paste")
			(net "DRV_ACT_29_35_N")
			(options
				(clearance outline)
				(anchor circle)
			)
			(primitives
				(gr_poly
					(pts
						(arc
							(start -0.1778 -0.5715)
							(mid -0.321484 -0.511984)
							(end -0.381 -0.3683)
						)
						(arc
							(start -0.381 0.3683)
							(mid -0.321484 0.511984)
							(end -0.1778 0.5715)
						)
						(arc
							(start 0.1778 0.5715)
							(mid 0.321484 0.511984)
							(end 0.381 0.3683)
						)
						(arc
							(start 0.381 -0.3683)
							(mid 0.321484 -0.511984)
							(end 0.1778 -0.5715)
						)
					)
					(width 0)
					(fill yes)
				)
			)
		)
		(pad "G" smd custom
			(at 0.98425 0.9525 180)
			(size 0.1905 0.1905)
			(layers "B.Cu" "B.Mask" "B.Paste")
			(net "DRIVE_A_29_35_ACT")
			(options
				(clearance outline)
				(anchor circle)
			)
			(primitives
				(gr_poly
					(pts
						(arc
							(start -0.1778 -0.5715)
							(mid -0.321484 -0.511984)
							(end -0.381 -0.3683)
						)
						(arc
							(start -0.381 0.3683)
							(mid -0.321484 0.511984)
							(end -0.1778 0.5715)
						)
						(arc
							(start 0.1778 0.5715)
							(mid 0.321484 0.511984)
							(end 0.381 0.3683)
						)
						(arc
							(start 0.381 -0.3683)
							(mid 0.321484 -0.511984)
							(end 0.1778 -0.5715)
						)
					)
					(width 0)
					(fill yes)
				)
			)
		)
		(pad "S" smd custom
			(at -0.98425 0.9525 180)
			(size 0.1905 0.1905)
			(layers "B.Cu" "B.Mask" "B.Paste")
			(net "GND")
			(options
				(clearance outline)
				(anchor circle)
			)
			(primitives
				(gr_poly
					(pts
						(arc
							(start -0.1778 -0.5715)
							(mid -0.321484 -0.511984)
							(end -0.381 -0.3683)
						)
						(arc
							(start -0.381 0.3683)
							(mid -0.321484 0.511984)
							(end -0.1778 0.5715)
						)
						(arc
							(start 0.1778 0.5715)
							(mid 0.321484 0.511984)
							(end 0.381 0.3683)
						)
						(arc
							(start 0.381 -0.3683)
							(mid 0.321484 -0.511984)
							(end 0.1778 -0.5715)
						)
					)
					(width 0)
					(fill yes)
				)
			)
		)
	)
	(footprint ""
		(layer "B.Cu")
		(at 106.4006 -5.9182)
		(property "Reference" "Q7"
			(at 0 0 0)
			(layer "B.SilkS")
			(hide yes)
			(effects
				(font
					(size 1.27 1.27)
				)
				(justify mirror)
			)
		)
		(property "Value" "2N7002K-2-GP"
			(at -0.127 -8.9662 0)
			(unlocked yes)
			(layer "B.Fab")
			(hide yes)
			(effects
				(font
					(size 1.016 1.016)
					(thickness 0.1524)
				)
				(justify mirror)
			)
		)
		(property "Device Type" "SOT23DGS2D4H44"
			(at -0.127 -10.4902 0)
			(unlocked yes)
			(layer "B.Fab")
			(hide yes)
			(effects
				(font
					(size 1.016 1.016)
					(thickness 0.1524)
				)
				(justify mirror)
			)
		)
		(duplicate_pad_numbers_are_jumpers no)
		(fp_line
			(start -1.651 -1.778)
			(end 1.651 -1.778)
			(stroke
				(width 0.1524)
				(type default)
			)
			(layer "B.SilkS")
		)
		(fp_line
			(start -1.651 1.778)
			(end -1.651 -1.778)
			(stroke
				(width 0.1524)
				(type default)
			)
			(layer "B.SilkS")
		)
		(fp_line
			(start 1.651 -1.778)
			(end 1.651 1.778)
			(stroke
				(width 0.1524)
				(type default)
			)
			(layer "B.SilkS")
		)
		(fp_line
			(start 1.651 1.778)
			(end -1.651 1.778)
			(stroke
				(width 0.1524)
				(type default)
			)
			(layer "B.SilkS")
		)
		(fp_poly
			(pts
				(xy 1.778 1.8796) (xy 1.778 -1.8796) (xy -1.778 -1.8796) (xy -1.778 1.8796)
			)
			(stroke
				(width 0)
				(type default)
			)
			(fill no)
			(layer "B.CrtYd")
		)
		(fp_poly
			(pts
				(xy 1.778 1.8796) (xy 1.778 -1.8796) (xy -1.778 -1.8796) (xy -1.778 1.8796)
			)
			(stroke
				(width 0)
				(type default)
			)
			(fill no)
			(layer "B.Fab")
		)
		(pad "D" smd custom
			(at 0 -0.9525 180)
			(size 0.1905 0.1905)
			(layers "B.Cu" "B.Mask" "B.Paste")
			(net "FLT_HDD27_33_N")
			(options
				(clearance outline)
				(anchor circle)
			)
			(primitives
				(gr_poly
					(pts
						(arc
							(start -0.1778 -0.5715)
							(mid -0.321484 -0.511984)
							(end -0.381 -0.3683)
						)
						(arc
							(start -0.381 0.3683)
							(mid -0.321484 0.511984)
							(end -0.1778 0.5715)
						)
						(arc
							(start 0.1778 0.5715)
							(mid 0.321484 0.511984)
							(end 0.381 0.3683)
						)
						(arc
							(start 0.381 -0.3683)
							(mid 0.321484 -0.511984)
							(end 0.1778 -0.5715)
						)
					)
					(width 0)
					(fill yes)
				)
			)
		)
		(pad "G" smd custom
			(at 0.98425 0.9525 180)
			(size 0.1905 0.1905)
			(layers "B.Cu" "B.Mask" "B.Paste")
			(net "DRIVE_A_27_33_FLT_LED")
			(options
				(clearance outline)
				(anchor circle)
			)
			(primitives
				(gr_poly
					(pts
						(arc
							(start -0.1778 -0.5715)
							(mid -0.321484 -0.511984)
							(end -0.381 -0.3683)
						)
						(arc
							(start -0.381 0.3683)
							(mid -0.321484 0.511984)
							(end -0.1778 0.5715)
						)
						(arc
							(start 0.1778 0.5715)
							(mid 0.321484 0.511984)
							(end 0.381 0.3683)
						)
						(arc
							(start 0.381 -0.3683)
							(mid 0.321484 -0.511984)
							(end 0.1778 -0.5715)
						)
					)
					(width 0)
					(fill yes)
				)
			)
		)
		(pad "S" smd custom
			(at -0.98425 0.9525 180)
			(size 0.1905 0.1905)
			(layers "B.Cu" "B.Mask" "B.Paste")
			(net "GND")
			(options
				(clearance outline)
				(anchor circle)
			)
			(primitives
				(gr_poly
					(pts
						(arc
							(start -0.1778 -0.5715)
							(mid -0.321484 -0.511984)
							(end -0.381 -0.3683)
						)
						(arc
							(start -0.381 0.3683)
							(mid -0.321484 0.511984)
							(end -0.1778 0.5715)
						)
						(arc
							(start 0.1778 0.5715)
							(mid 0.321484 0.511984)
							(end 0.381 0.3683)
						)
						(arc
							(start 0.381 -0.3683)
							(mid 0.321484 -0.511984)
							(end 0.1778 -0.5715)
						)
					)
					(width 0)
					(fill yes)
				)
			)
		)
	)
	(footprint ""
		(layer "B.Cu")
		(at 16.3322 -5.8166 180)
		(property "Reference" "R1"
			(at 0 0 0)
			(layer "B.SilkS")
			(hide yes)
			(effects
				(font
					(size 1.27 1.27)
				)
				(justify mirror)
			)
		)
		(property "Value" "130R3F-GP"
			(at 0.0254 -2.5146 180)
			(unlocked yes)
			(layer "B.Fab")
			(hide yes)
			(effects
				(font
					(size 1.016 1.016)
					(thickness 0.1524)
				)
				(justify mirror)
			)
		)
		(property "Device Type" "R603H22"
			(at 0.0254 -4.0386 180)
			(unlocked yes)
			(layer "B.Fab")
			(hide yes)
			(effects
				(font
					(size 1.016 1.016)
					(thickness 0.1524)
				)
				(justify mirror)
			)
		)
		(duplicate_pad_numbers_are_jumpers no)
		(fp_line
			(start 0.4826 0)
			(end 0.2032 0)
			(stroke
				(width 0.2032)
				(type default)
			)
			(layer "B.SilkS")
		)
		(fp_line
			(start -0.2032 0)
			(end -0.4826 0)
			(stroke
				(width 0.2032)
				(type default)
			)
			(layer "B.SilkS")
		)
		(fp_rect
			(start 0.5842 1.3335)
			(end -0.5842 -1.3335)
			(stroke
				(width 0)
				(type default)
			)
			(fill no)
			(layer "B.CrtYd")
		)
		(fp_rect
			(start 0.5842 1.3335)
			(end -0.5842 -1.3335)
			(stroke
				(width 0)
				(type default)
			)
			(fill no)
			(layer "B.Fab")
		)
		(pad "1" smd custom
			(at 0 -0.762)
			(size 0.2159 0.2159)
			(layers "B.Cu" "B.Mask" "B.Paste")
			(net "P5V_A")
			(options
				(clearance outline)
				(anchor circle)
			)
			(primitives
				(gr_poly
					(pts
						(arc
							(start -0.3302 0.4318)
							(mid -0.402042 0.402042)
							(end -0.4318 0.3302)
						)
						(arc
							(start -0.4318 -0.3302)
							(mid -0.402042 -0.402042)
							(end -0.3302 -0.4318)
						)
						(arc
							(start 0.3302 -0.4318)
							(mid 0.402042 -0.402042)
							(end 0.4318 -0.3302)
						)
						(arc
							(start 0.4318 0.3302)
							(mid 0.402042 0.402042)
							(end 0.3302 0.4318)
						)
					)
					(width 0)
					(fill yes)
				)
			)
		)
		(pad "2" smd custom
			(at 0 0.762)
			(size 0.2159 0.2159)
			(layers "B.Cu" "B.Mask" "B.Paste")
			(net "FLT_HDD24_30")
			(options
				(clearance outline)
				(anchor circle)
			)
			(primitives
				(gr_poly
					(pts
						(arc
							(start -0.3302 0.4318)
							(mid -0.402042 0.402042)
							(end -0.4318 0.3302)
						)
						(arc
							(start -0.4318 -0.3302)
							(mid -0.402042 -0.402042)
							(end -0.3302 -0.4318)
						)
						(arc
							(start 0.3302 -0.4318)
							(mid 0.402042 -0.402042)
							(end 0.4318 -0.3302)
						)
						(arc
							(start 0.4318 0.3302)
							(mid 0.402042 0.402042)
							(end 0.3302 0.4318)
						)
					)
					(width 0)
					(fill yes)
				)
			)
		)
	)
	(footprint ""
		(layer "B.Cu")
		(at 70.757796 -6.06298 180)
		(property "Reference" "R6"
			(at 0 0 0)
			(layer "B.SilkS")
			(hide yes)
			(effects
				(font
					(size 1.27 1.27)
				)
				(justify mirror)
			)
		)
		(property "Value" "91R3F-1-GP"
			(at 0.0254 -2.5146 180)
			(unlocked yes)
			(layer "B.Fab")
			(hide yes)
			(effects
				(font
					(size 1.016 1.016)
					(thickness 0.1524)
				)
				(justify mirror)
			)
		)
		(property "Device Type" "R603H22"
			(at 0.0254 -4.0386 180)
			(unlocked yes)
			(layer "B.Fab")
			(hide yes)
			(effects
				(font
					(size 1.016 1.016)
					(thickness 0.1524)
				)
				(justify mirror)
			)
		)
		(duplicate_pad_numbers_are_jumpers no)
		(fp_line
			(start 0.4826 0)
			(end 0.2032 0)
			(stroke
				(width 0.2032)
				(type default)
			)
			(layer "B.SilkS")
		)
		(fp_line
			(start -0.2032 0)
			(end -0.4826 0)
			(stroke
				(width 0.2032)
				(type default)
			)
			(layer "B.SilkS")
		)
		(fp_rect
			(start 0.5842 1.3335)
			(end -0.5842 -1.3335)
			(stroke
				(width 0)
				(type default)
			)
			(fill no)
			(layer "B.CrtYd")
		)
		(fp_rect
			(start 0.5842 1.3335)
			(end -0.5842 -1.3335)
			(stroke
				(width 0)
				(type default)
			)
			(fill no)
			(layer "B.Fab")
		)
		(pad "1" smd custom
			(at 0 -0.762)
			(size 0.2159 0.2159)
			(layers "B.Cu" "B.Mask" "B.Paste")
			(net "P5V_A")
			(options
				(clearance outline)
				(anchor circle)
			)
			(primitives
				(gr_poly
					(pts
						(arc
							(start -0.3302 0.4318)
							(mid -0.402042 0.402042)
							(end -0.4318 0.3302)
						)
						(arc
							(start -0.4318 -0.3302)
							(mid -0.402042 -0.402042)
							(end -0.3302 -0.4318)
						)
						(arc
							(start 0.3302 -0.4318)
							(mid 0.402042 -0.402042)
							(end 0.4318 -0.3302)
						)
						(arc
							(start 0.4318 0.3302)
							(mid 0.402042 0.402042)
							(end 0.3302 0.4318)
						)
					)
					(width 0)
					(fill yes)
				)
			)
		)
		(pad "2" smd custom
			(at 0 0.762)
			(size 0.2159 0.2159)
			(layers "B.Cu" "B.Mask" "B.Paste")
			(net "DRV_ACT_26_32")
			(options
				(clearance outline)
				(anchor circle)
			)
			(primitives
				(gr_poly
					(pts
						(arc
							(start -0.3302 0.4318)
							(mid -0.402042 0.402042)
							(end -0.4318 0.3302)
						)
						(arc
							(start -0.4318 -0.3302)
							(mid -0.402042 -0.402042)
							(end -0.3302 -0.4318)
						)
						(arc
							(start 0.3302 -0.4318)
							(mid 0.402042 -0.402042)
							(end 0.4318 -0.3302)
						)
						(arc
							(start 0.4318 0.3302)
							(mid 0.402042 0.402042)
							(end 0.3302 0.4318)
						)
					)
					(width 0)
					(fill yes)
				)
			)
		)
	)
)
